(kicad_pcb
	(version 20260206)
	(generator "pcbnew")
	(generator_version "10.0")
	(general
		(thickness 1.6)
		(legacy_teardrops no)
	)
	(paper "A4")
	(title_block
		(title "Bryce Canyon_IOM_IOC_16318-2_OCP.brd")
		(comment 1 "Bryce Canyon / footprints 966-973 of 1605")
	)
	(layers
		(0 "F.Cu" signal "TOP")
		(4 "In1.Cu" signal "L2GND")
		(6 "In2.Cu" signal "L3")
		(8 "In3.Cu" signal "L4VCC")
		(10 "In4.Cu" signal "L5VCC")
		(12 "In5.Cu" signal "L6")
		(14 "In6.Cu" signal "L7GND")
		(2 "B.Cu" signal "BOTTOM")
		(9 "F.Adhes" user "F.Adhesive")
		(11 "B.Adhes" user "B.Adhesive")
		(13 "F.Paste" user "Package Geometry/Pastemask Top")
		(15 "B.Paste" user "Package Geometry/Pastemask Bottom")
		(5 "F.SilkS" user "Ref Des/Silkscreen Top")
		(7 "B.SilkS" user "Ref Des/Silkscreen Bottom")
		(1 "F.Mask" user "Board Geometry/Soldermask Top")
		(3 "B.Mask" user "Board Geometry/Soldermask Bottom")
		(17 "Dwgs.User" user "User.Drawings")
		(19 "Cmts.User" user "User.Comments")
		(21 "Eco1.User" user "User.Eco1")
		(23 "Eco2.User" user "User.Eco2")
		(25 "Edge.Cuts" user "Board Geometry/Outline")
		(27 "Margin" user)
		(31 "F.CrtYd" user "Package Geometry/Place Bound Top")
		(29 "B.CrtYd" user "Package Geometry/Place Bound Bottom")
		(35 "F.Fab" user "Ref Des/Assembly Top")
		(33 "B.Fab" user "Ref Des/Assembly Bottom")
	)
	(footprint ""
		(layer "B.Cu")
		(at 79.317088 -49.922176 180)
		(property "Reference" "C28"
			(at 0 0 0)
			(layer "B.SilkS")
			(hide yes)
			(effects
				(font
					(size 1.27 1.27)
				)
				(justify mirror)
			)
		)
		(property "Value" "SC2D2U25V5KX-2-GP"
			(at 0.0762 -6.1214 180)
			(unlocked yes)
			(layer "B.Fab")
			(hide yes)
			(effects
				(font
					(size 1.016 1.016)
					(thickness 0.1524)
				)
				(justify mirror)
			)
		)
		(property "Device Type" "C805H54"
			(at 0.0762 -8.1534 180)
			(unlocked yes)
			(layer "B.Fab")
			(hide yes)
			(effects
				(font
					(size 1.016 1.016)
					(thickness 0.1524)
				)
				(justify mirror)
			)
		)
		(duplicate_pad_numbers_are_jumpers no)
		(fp_line
			(start -0.635 0)
			(end 0.635 0)
			(stroke
				(width 0.508)
				(type default)
			)
			(layer "B.SilkS")
		)
		(fp_rect
			(start 0.9652 1.778)
			(end -0.9652 -1.778)
			(stroke
				(width 0)
				(type default)
			)
			(fill no)
			(layer "B.CrtYd")
		)
		(fp_poly
			(pts
				(xy 0.9652 -1.778) (xy -0.9652 -1.778) (xy -0.9652 1.778) (xy 0.9652 1.778)
			)
			(stroke
				(width 0)
				(type default)
			)
			(fill no)
			(layer "B.Fab")
		)
		(pad "1" smd rect
			(at 0 -0.9652)
			(size 1.397 1.143)
			(layers "B.Cu" "B.Mask" "B.Paste")
			(net "P12V_STBY")
		)
		(pad "2" smd rect
			(at 0 0.9652)
			(size 1.397 1.143)
			(layers "B.Cu" "B.Mask" "B.Paste")
			(net "GND")
		)
	)
	(footprint ""
		(layer "B.Cu")
		(at 180.601366 -70.894956)
		(property "Reference" "TP116"
			(at 0 0 0)
			(layer "B.SilkS")
			(hide yes)
			(effects
				(font
					(size 1.27 1.27)
				)
				(justify mirror)
			)
		)
		(property "Value" "TPAD28-2-GP"
			(at 0.0127 -1.6637 0)
			(unlocked yes)
			(layer "B.Fab")
			(hide yes)
			(effects
				(font
					(size 1.016 1.016)
					(thickness 0.1524)
				)
				(justify mirror)
			)
		)
		(property "Device Type" "TPAD28"
			(at 0.0127 -3.1877 0)
			(unlocked yes)
			(layer "B.Fab")
			(hide yes)
			(effects
				(font
					(size 1.016 1.016)
					(thickness 0.1524)
				)
				(justify mirror)
			)
		)
		(duplicate_pad_numbers_are_jumpers no)
		(fp_poly
			(pts
				(arc
					(start 0.3556 0)
					(mid -0.3556 0)
					(end 0.3556 0)
				)
			)
			(stroke
				(width 0)
				(type default)
			)
			(fill no)
			(layer "B.CrtYd")
		)
		(fp_poly
			(pts
				(arc
					(start 0.6096 0)
					(mid -0.6096 0)
					(end 0.6096 0)
				)
			)
			(stroke
				(width 0)
				(type default)
			)
			(fill no)
			(layer "B.Fab")
		)
		(pad "1" smd circle
			(at 0 0 180)
			(size 0.7112 0.7112)
			(layers "B.Cu" "B.Mask" "B.Paste")
			(net "IOC_GPIO_28")
		)
	)
	(footprint ""
		(layer "B.Cu")
		(at 90.8812 -137.5156 -90)
		(property "Reference" "C504"
			(at 0 0 90)
			(layer "B.SilkS")
			(hide yes)
			(effects
				(font
					(size 1.27 1.27)
				)
				(justify mirror)
			)
		)
		(property "Value" "SCD1U16V2KX-3GP"
			(at -1.1811 -2.7051 270)
			(unlocked yes)
			(layer "B.Fab")
			(hide yes)
			(effects
				(font
					(size 1.016 1.016)
					(thickness 0.1524)
				)
				(justify mirror)
			)
		)
		(property "Device Type" "C402H22"
			(at -1.1811 -4.2291 270)
			(unlocked yes)
			(layer "B.Fab")
			(hide yes)
			(effects
				(font
					(size 1.016 1.016)
					(thickness 0.1524)
				)
				(justify mirror)
			)
		)
		(duplicate_pad_numbers_are_jumpers no)
		(fp_rect
			(start 0.4318 0.9525)
			(end -0.4318 -0.9525)
			(stroke
				(width 0)
				(type default)
			)
			(fill no)
			(layer "B.CrtYd")
		)
		(fp_rect
			(start 0.4318 0.9525)
			(end -0.4318 -0.9525)
			(stroke
				(width 0)
				(type default)
			)
			(fill no)
			(layer "B.Fab")
		)
		(pad "1" smd custom
			(at 0 -0.4445 90)
			(size 0.1524 0.1524)
			(layers "B.Cu" "B.Mask" "B.Paste")
			(net "P3V3_STBY")
			(options
				(clearance outline)
				(anchor circle)
			)
			(primitives
				(gr_poly
					(pts
						(arc
							(start 0.3048 0.2032)
							(mid 0.275042 0.275042)
							(end 0.2032 0.3048)
						)
						(arc
							(start -0.2032 0.3048)
							(mid -0.275042 0.275042)
							(end -0.3048 0.2032)
						)
						(arc
							(start -0.3048 -0.2032)
							(mid -0.275042 -0.275042)
							(end -0.2032 -0.3048)
						)
						(arc
							(start 0.2032 -0.3048)
							(mid 0.275042 -0.275042)
							(end 0.3048 -0.2032)
						)
					)
					(width 0)
					(fill yes)
				)
			)
		)
		(pad "2" smd custom
			(at 0 0.4445 90)
			(size 0.1524 0.1524)
			(layers "B.Cu" "B.Mask" "B.Paste")
			(net "GND")
			(options
				(clearance outline)
				(anchor circle)
			)
			(primitives
				(gr_poly
					(pts
						(arc
							(start 0.3048 0.2032)
							(mid 0.275042 0.275042)
							(end 0.2032 0.3048)
						)
						(arc
							(start -0.2032 0.3048)
							(mid -0.275042 0.275042)
							(end -0.3048 0.2032)
						)
						(arc
							(start -0.3048 -0.2032)
							(mid -0.275042 -0.275042)
							(end -0.2032 -0.3048)
						)
						(arc
							(start 0.2032 -0.3048)
							(mid 0.275042 -0.275042)
							(end 0.3048 -0.2032)
						)
					)
					(width 0)
					(fill yes)
				)
			)
		)
	)
	(footprint ""
		(layer "B.Cu")
		(at 170.6118 -78.0796 90)
		(property "Reference" "R682"
			(at 0 0 90)
			(layer "B.SilkS")
			(hide yes)
			(effects
				(font
					(size 1.27 1.27)
				)
				(justify mirror)
			)
		)
		(property "Value" "10R2F-L-GP"
			(at -0.064008 -3.993896 90)
			(unlocked yes)
			(layer "B.Fab")
			(hide yes)
			(effects
				(font
					(size 1.016 1.016)
					(thickness 0.1524)
				)
				(justify mirror)
			)
		)
		(property "Device Type" "R402H14"
			(at -0.064008 -5.517896 90)
			(unlocked yes)
			(layer "B.Fab")
			(hide yes)
			(effects
				(font
					(size 1.016 1.016)
					(thickness 0.1524)
				)
				(justify mirror)
			)
		)
		(duplicate_pad_numbers_are_jumpers no)
		(fp_line
			(start 0.508 -0.9398)
			(end 0.508 0.9398)
			(stroke
				(width 0.1524)
				(type default)
			)
			(layer "B.SilkS")
		)
		(fp_line
			(start -0.508 -0.9398)
			(end 0.508 -0.9398)
			(stroke
				(width 0.1524)
				(type default)
			)
			(layer "B.SilkS")
		)
		(fp_rect
			(start 0.508 0.9398)
			(end -0.508 -0.9398)
			(stroke
				(width 0)
				(type default)
			)
			(fill no)
			(layer "B.CrtYd")
		)
		(fp_rect
			(start 0.508 0.9398)
			(end -0.508 -0.9398)
			(stroke
				(width 0)
				(type default)
			)
			(fill no)
			(layer "B.Fab")
		)
		(pad "1" smd custom
			(at 0 -0.4445 270)
			(size 0.1397 0.1397)
			(layers "B.Cu" "B.Mask" "B.Paste")
			(net "P1V8")
			(options
				(clearance outline)
				(anchor circle)
			)
			(primitives
				(gr_poly
					(pts
						(arc
							(start -0.1778 0.2794)
							(mid -0.249642 0.249642)
							(end -0.2794 0.1778)
						)
						(arc
							(start -0.2794 -0.1778)
							(mid -0.249642 -0.249642)
							(end -0.1778 -0.2794)
						)
						(arc
							(start 0.1778 -0.2794)
							(mid 0.249642 -0.249642)
							(end 0.2794 -0.1778)
						)
						(arc
							(start 0.2794 0.1778)
							(mid 0.249642 0.249642)
							(end 0.1778 0.2794)
						)
					)
					(width 0)
					(fill yes)
				)
			)
		)
		(pad "2" smd custom
			(at 0 0.4445 270)
			(size 0.1397 0.1397)
			(layers "B.Cu" "B.Mask" "B.Paste")
			(net "PLL_VDD")
			(options
				(clearance outline)
				(anchor circle)
			)
			(primitives
				(gr_poly
					(pts
						(arc
							(start -0.1778 0.2794)
							(mid -0.249642 0.249642)
							(end -0.2794 0.1778)
						)
						(arc
							(start -0.2794 -0.1778)
							(mid -0.249642 -0.249642)
							(end -0.1778 -0.2794)
						)
						(arc
							(start 0.1778 -0.2794)
							(mid 0.249642 -0.249642)
							(end 0.2794 -0.1778)
						)
						(arc
							(start 0.2794 0.1778)
							(mid 0.249642 0.249642)
							(end 0.1778 0.2794)
						)
					)
					(width 0)
					(fill yes)
				)
			)
		)
	)
	(footprint ""
		(layer "B.Cu")
		(at 64.17818 -158.048198 180)
		(property "Reference" "C80"
			(at 0 0 0)
			(layer "B.SilkS")
			(hide yes)
			(effects
				(font
					(size 1.27 1.27)
				)
				(justify mirror)
			)
		)
		(property "Value" "SCD1U16V2KX-3GP"
			(at -1.1811 -2.7051 180)
			(unlocked yes)
			(layer "B.Fab")
			(hide yes)
			(effects
				(font
					(size 1.016 1.016)
					(thickness 0.1524)
				)
				(justify mirror)
			)
		)
		(property "Device Type" "C402H22"
			(at -1.1811 -4.2291 180)
			(unlocked yes)
			(layer "B.Fab")
			(hide yes)
			(effects
				(font
					(size 1.016 1.016)
					(thickness 0.1524)
				)
				(justify mirror)
			)
		)
		(duplicate_pad_numbers_are_jumpers no)
		(fp_rect
			(start 0.4318 0.9525)
			(end -0.4318 -0.9525)
			(stroke
				(width 0)
				(type default)
			)
			(fill no)
			(layer "B.CrtYd")
		)
		(fp_rect
			(start 0.4318 0.9525)
			(end -0.4318 -0.9525)
			(stroke
				(width 0)
				(type default)
			)
			(fill no)
			(layer "B.Fab")
		)
		(pad "1" smd custom
			(at 0 -0.4445)
			(size 0.1524 0.1524)
			(layers "B.Cu" "B.Mask" "B.Paste")
			(net "P3V3_STBY")
			(options
				(clearance outline)
				(anchor circle)
			)
			(primitives
				(gr_poly
					(pts
						(arc
							(start 0.3048 0.2032)
							(mid 0.275042 0.275042)
							(end 0.2032 0.3048)
						)
						(arc
							(start -0.2032 0.3048)
							(mid -0.275042 0.275042)
							(end -0.3048 0.2032)
						)
						(arc
							(start -0.3048 -0.2032)
							(mid -0.275042 -0.275042)
							(end -0.2032 -0.3048)
						)
						(arc
							(start 0.2032 -0.3048)
							(mid 0.275042 -0.275042)
							(end 0.3048 -0.2032)
						)
					)
					(width 0)
					(fill yes)
				)
			)
		)
		(pad "2" smd custom
			(at 0 0.4445)
			(size 0.1524 0.1524)
			(layers "B.Cu" "B.Mask" "B.Paste")
			(net "GND")
			(options
				(clearance outline)
				(anchor circle)
			)
			(primitives
				(gr_poly
					(pts
						(arc
							(start 0.3048 0.2032)
							(mid 0.275042 0.275042)
							(end 0.2032 0.3048)
						)
						(arc
							(start -0.2032 0.3048)
							(mid -0.275042 0.275042)
							(end -0.3048 0.2032)
						)
						(arc
							(start -0.3048 -0.2032)
							(mid -0.275042 -0.275042)
							(end -0.2032 -0.3048)
						)
						(arc
							(start 0.2032 -0.3048)
							(mid 0.275042 -0.275042)
							(end 0.3048 -0.2032)
						)
					)
					(width 0)
					(fill yes)
				)
			)
		)
	)
	(footprint ""
		(layer "B.Cu")
		(at 52.07508 -155.05176)
		(property "Reference" "R315"
			(at 0 0 0)
			(layer "B.SilkS")
			(hide yes)
			(effects
				(font
					(size 1.27 1.27)
				)
				(justify mirror)
			)
		)
		(property "Value" "10KR2F-2-GP"
			(at -0.064008 -3.993896 0)
			(unlocked yes)
			(layer "B.Fab")
			(hide yes)
			(effects
				(font
					(size 1.016 1.016)
					(thickness 0.1524)
				)
				(justify mirror)
			)
		)
		(property "Device Type" "R402H16"
			(at -0.064008 -5.517896 0)
			(unlocked yes)
			(layer "B.Fab")
			(hide yes)
			(effects
				(font
					(size 1.016 1.016)
					(thickness 0.1524)
				)
				(justify mirror)
			)
		)
		(duplicate_pad_numbers_are_jumpers no)
		(fp_line
			(start -0.508 -0.9398)
			(end 0.508 -0.9398)
			(stroke
				(width 0.1524)
				(type default)
			)
			(layer "B.SilkS")
		)
		(fp_line
			(start 0.508 -0.9398)
			(end 0.508 0.9398)
			(stroke
				(width 0.1524)
				(type default)
			)
			(layer "B.SilkS")
		)
		(fp_rect
			(start 0.508 0.9398)
			(end -0.508 -0.9398)
			(stroke
				(width 0)
				(type default)
			)
			(fill no)
			(layer "B.CrtYd")
		)
		(fp_rect
			(start 0.508 0.9398)
			(end -0.508 -0.9398)
			(stroke
				(width 0)
				(type default)
			)
			(fill no)
			(layer "B.Fab")
		)
		(pad "1" smd custom
			(at 0 -0.4445 180)
			(size 0.1397 0.1397)
			(layers "B.Cu" "B.Mask" "B.Paste")
			(net "BMC_ENTEST")
			(options
				(clearance outline)
				(anchor circle)
			)
			(primitives
				(gr_poly
					(pts
						(arc
							(start -0.1778 0.2794)
							(mid -0.249642 0.249642)
							(end -0.2794 0.1778)
						)
						(arc
							(start -0.2794 -0.1778)
							(mid -0.249642 -0.249642)
							(end -0.1778 -0.2794)
						)
						(arc
							(start 0.1778 -0.2794)
							(mid 0.249642 -0.249642)
							(end 0.2794 -0.1778)
						)
						(arc
							(start 0.2794 0.1778)
							(mid 0.249642 0.249642)
							(end 0.1778 0.2794)
						)
					)
					(width 0)
					(fill yes)
				)
			)
		)
		(pad "2" smd custom
			(at 0 0.4445 180)
			(size 0.1397 0.1397)
			(layers "B.Cu" "B.Mask" "B.Paste")
			(net "GND")
			(options
				(clearance outline)
				(anchor circle)
			)
			(primitives
				(gr_poly
					(pts
						(arc
							(start -0.1778 0.2794)
							(mid -0.249642 0.249642)
							(end -0.2794 0.1778)
						)
						(arc
							(start -0.2794 -0.1778)
							(mid -0.249642 -0.249642)
							(end -0.1778 -0.2794)
						)
						(arc
							(start 0.1778 -0.2794)
							(mid 0.249642 -0.249642)
							(end 0.2794 -0.1778)
						)
						(arc
							(start 0.2794 0.1778)
							(mid 0.249642 0.249642)
							(end 0.1778 0.2794)
						)
					)
					(width 0)
					(fill yes)
				)
			)
		)
	)
	(footprint ""
		(layer "B.Cu")
		(at 50.81397 -132.626354)
		(property "Reference" "C113"
			(at 0 0 0)
			(layer "B.SilkS")
			(hide yes)
			(effects
				(font
					(size 1.27 1.27)
				)
				(justify mirror)
			)
		)
		(property "Value" "SC1U16V3KX-5GP"
			(at 0 -2.8194 0)
			(unlocked yes)
			(layer "B.Fab")
			(hide yes)
			(effects
				(font
					(size 1.016 1.016)
					(thickness 0.1524)
				)
				(justify mirror)
			)
		)
		(property "Device Type" "C603H36"
			(at 0 -4.3434 0)
			(unlocked yes)
			(layer "B.Fab")
			(hide yes)
			(effects
				(font
					(size 1.016 1.016)
					(thickness 0.1524)
				)
				(justify mirror)
			)
		)
		(duplicate_pad_numbers_are_jumpers no)
		(fp_line
			(start -0.508 0)
			(end 0.508 0)
			(stroke
				(width 0.2032)
				(type default)
			)
			(layer "B.SilkS")
		)
		(fp_rect
			(start 0.5842 1.3335)
			(end -0.5842 -1.3335)
			(stroke
				(width 0)
				(type default)
			)
			(fill no)
			(layer "B.CrtYd")
		)
		(fp_rect
			(start 0.5842 1.3335)
			(end -0.5842 -1.3335)
			(stroke
				(width 0)
				(type default)
			)
			(fill no)
			(layer "B.Fab")
		)
		(pad "1" smd custom
			(at 0 -0.762 180)
			(size 0.2159 0.2159)
			(layers "B.Cu" "B.Mask" "B.Paste")
			(net "P1V15_STBY")
			(options
				(clearance outline)
				(anchor circle)
			)
			(primitives
				(gr_poly
					(pts
						(arc
							(start -0.3302 0.4318)
							(mid -0.402042 0.402042)
							(end -0.4318 0.3302)
						)
						(arc
							(start -0.4318 -0.3302)
							(mid -0.402042 -0.402042)
							(end -0.3302 -0.4318)
						)
						(arc
							(start 0.3302 -0.4318)
							(mid 0.402042 -0.402042)
							(end 0.4318 -0.3302)
						)
						(arc
							(start 0.4318 0.3302)
							(mid 0.402042 0.402042)
							(end 0.3302 0.4318)
						)
					)
					(width 0)
					(fill yes)
				)
			)
		)
		(pad "2" smd custom
			(at 0 0.762 180)
			(size 0.2159 0.2159)
			(layers "B.Cu" "B.Mask" "B.Paste")
			(net "GND")
			(options
				(clearance outline)
				(anchor circle)
			)
			(primitives
				(gr_poly
					(pts
						(arc
							(start -0.3302 0.4318)
							(mid -0.402042 0.402042)
							(end -0.4318 0.3302)
						)
						(arc
							(start -0.4318 -0.3302)
							(mid -0.402042 -0.402042)
							(end -0.3302 -0.4318)
						)
						(arc
							(start 0.3302 -0.4318)
							(mid 0.402042 -0.402042)
							(end 0.4318 -0.3302)
						)
						(arc
							(start 0.4318 0.3302)
							(mid 0.402042 0.402042)
							(end 0.3302 0.4318)
						)
					)
					(width 0)
					(fill yes)
				)
			)
		)
	)
	(footprint ""
		(layer "B.Cu")
		(at 168.601136 -38.442138)
		(property "Reference" "C496"
			(at 0 0 0)
			(layer "B.SilkS")
			(hide yes)
			(effects
				(font
					(size 1.27 1.27)
				)
				(justify mirror)
			)
		)
		(property "Value" "SCD01U16V1KX-GP"
			(at 2.8321 -1.7399 0)
			(unlocked yes)
			(layer "B.Fab")
			(hide yes)
			(effects
				(font
					(size 1.016 1.016)
					(thickness 0.1524)
				)
				(justify mirror)
			)
		)
		(property "Device Type" "C0201H13"
			(at 2.8321 -3.2639 0)
			(unlocked yes)
			(layer "B.Fab")
			(hide yes)
			(effects
				(font
					(size 1.016 1.016)
					(thickness 0.1524)
				)
				(justify mirror)
			)
		)
		(duplicate_pad_numbers_are_jumpers no)
		(fp_rect
			(start 0.2794 0.6477)
			(end -0.2794 -0.6477)
			(stroke
				(width 0)
				(type default)
			)
			(fill no)
			(layer "B.CrtYd")
		)
		(fp_rect
			(start 0.2794 0.6477)
			(end -0.2794 -0.6477)
			(stroke
				(width 0)
				(type default)
			)
			(fill no)
			(layer "B.Fab")
		)
		(pad "1" smd custom
			(at 0 -0.2794 180)
			(size 0.0762 0.0762)
			(layers "B.Cu" "B.Mask" "B.Paste")
			(net "PHY_CON_B_TO_IOC_1_DN")
			(options
				(clearance outline)
				(anchor circle)
			)
			(primitives
				(gr_poly
					(pts
						(arc
							(start 0.1524 0.127)
							(mid 0.137521 0.162921)
							(end 0.1016 0.1778)
						)
						(arc
							(start -0.1016 0.1778)
							(mid -0.137521 0.162921)
							(end -0.1524 0.127)
						)
						(arc
							(start -0.1524 -0.127)
							(mid -0.137521 -0.162921)
							(end -0.1016 -0.1778)
						)
						(arc
							(start 0.1016 -0.1778)
							(mid 0.137521 -0.162921)
							(end 0.1524 -0.127)
						)
					)
					(width 0)
					(fill yes)
				)
			)
		)
		(pad "2" smd custom
			(at 0 0.2794 180)
			(size 0.0762 0.0762)
			(layers "B.Cu" "B.Mask" "B.Paste")
			(net "PHY_CON_B_TO_IOC_1_DN_C")
			(options
				(clearance outline)
				(anchor circle)
			)
			(primitives
				(gr_poly
					(pts
						(arc
							(start 0.1524 0.127)
							(mid 0.137521 0.162921)
							(end 0.1016 0.1778)
						)
						(arc
							(start -0.1016 0.1778)
							(mid -0.137521 0.162921)
							(end -0.1524 0.127)
						)
						(arc
							(start -0.1524 -0.127)
							(mid -0.137521 -0.162921)
							(end -0.1016 -0.1778)
						)
						(arc
							(start 0.1016 -0.1778)
							(mid 0.137521 -0.162921)
							(end 0.1524 -0.127)
						)
					)
					(width 0)
					(fill yes)
				)
			)
		)
	)
)
